# S9S_MB_2U (Grand Teton) — schematic netlist excerpt (pin names and nets, part order shuffled) for the footprints in the layout excerpt that follows; sources: Cadence DE-HDL packaged netlist, KiCad conversion of 03242023_DA0F0TMBIJ0_F0T_Motherboard_J_brd_V01_OCP.brd

R2563  Q_RES  0 5% CHIP  pkg 0402LF  page 292 : A = SMB_VR_3V3AUX_SDA_R ; B = SMB_DIO_PVCCINFAON_CPU1
C748  Q_CAP_DIFFBUS  DIFF BUS_0.22UF 6.3V 20% X6S  pkg C0201  page 176 : \1\ = P5E_CPU1_PE2_TX_C_DN<12> ; \2\ = P5E_CPU1_PE2_TX_DN<12>

(kicad_pcb
	(version 20260206)
	(generator "pcbnew")
	(generator_version "10.0")
	(general
		(thickness 1.6)
		(legacy_teardrops no)
	)
	(paper "A4")
	(title_block
		(title "03242023_DA0F0TMBIJ0_F0T_Motherboard_J_brd_V01_OCP.brd")
		(comment 1 "Grand Teton / footprints 2082-2083 of 6105")
	)
	(layers
		(0 "F.Cu" signal "TOP")
		(4 "In1.Cu" signal "GND")
		(6 "In2.Cu" signal "IN1")
		(8 "In3.Cu" signal "GND1")
		(10 "In4.Cu" signal "IN2")
		(12 "In5.Cu" signal "GND2")
		(14 "In6.Cu" signal "IN3")
		(16 "In7.Cu" signal "GND3")
		(18 "In8.Cu" signal "VCC")
		(20 "In9.Cu" signal "VCC1")
		(22 "In10.Cu" signal "GND4")
		(24 "In11.Cu" signal "IN4")
		(26 "In12.Cu" signal "GND5")
		(28 "In13.Cu" signal "IN5")
		(30 "In14.Cu" signal "GND6")
		(32 "In15.Cu" signal "IN6")
		(34 "In16.Cu" signal "GND7")
		(2 "B.Cu" signal "BOTTOM")
		(9 "F.Adhes" user "F.Adhesive")
		(11 "B.Adhes" user "B.Adhesive")
		(13 "F.Paste" user "Package Geometry/Pastemask Top")
		(15 "B.Paste" user "Package Geometry/Pastemask Bottom")
		(5 "F.SilkS" user "Ref Des/Silkscreen Top")
		(7 "B.SilkS" user "Ref Des/Silkscreen Bottom")
		(1 "F.Mask" user "Board Geometry/Soldermask Top")
		(3 "B.Mask" user "Board Geometry/Soldermask Bottom")
		(17 "Dwgs.User" user "User.Drawings")
		(19 "Cmts.User" user "User.Comments")
		(21 "Eco1.User" user "User.Eco1")
		(23 "Eco2.User" user "User.Eco2")
		(25 "Edge.Cuts" user "Board Geometry/Outline")
		(27 "Margin" user)
		(31 "F.CrtYd" user "Package Geometry/Place Bound Top")
		(29 "B.CrtYd" user "Package Geometry/Place Bound Bottom")
		(35 "F.Fab" user "Ref Des/Assembly Top")
		(33 "B.Fab" user "Ref Des/Assembly Bottom")
	)
	(footprint ""
		(layer "F.Cu")
		(at 130.233674 -402.371052 -90)
		(property "Reference" "C748"
			(at 0 0 270)
			(layer "F.SilkS")
			(hide yes)
			(effects
				(font
					(size 1.27 1.27)
				)
			)
		)
		(property "Value" ""
			(at 0 0 270)
			(layer "F.Fab")
			(effects
				(font
					(size 1.27 1.27)
				)
			)
		)
		(duplicate_pad_numbers_are_jumpers no)
		(fp_line
			(start -0.299974 0.150114)
			(end -0.299974 -0.150114)
			(stroke
				(width 0.1)
				(type default)
			)
			(layer "F.Fab")
		)
		(fp_line
			(start 0.299974 0.150114)
			(end -0.299974 0.150114)
			(stroke
				(width 0.1)
				(type default)
			)
			(layer "F.Fab")
		)
		(fp_line
			(start -0.299974 -0.150114)
			(end 0.299974 -0.150114)
			(stroke
				(width 0.1)
				(type default)
			)
			(layer "F.Fab")
		)
		(fp_line
			(start 0.299974 -0.150114)
			(end 0.299974 0.150114)
			(stroke
				(width 0.1)
				(type default)
			)
			(layer "F.Fab")
		)
		(pad "1" smd rect
			(at -0.2667 0 270)
			(size 0.3048 0.381)
			(layers "F.Cu" "F.Mask" "F.Paste")
			(net "P5E_CPU1_PE2_TX_C_DN<12>")
		)
		(pad "2" smd rect
			(at 0.2667 0 270)
			(size 0.3048 0.381)
			(layers "F.Cu" "F.Mask" "F.Paste")
			(net "P5E_CPU1_PE2_TX_DN<12>")
		)
	)
	(footprint ""
		(layer "F.Cu")
		(at 33.021524 -124.99721 90)
		(property "Reference" "R2563"
			(at 0 0 90)
			(layer "F.SilkS")
			(hide yes)
			(effects
				(font
					(size 1.27 1.27)
				)
			)
		)
		(property "Value" ""
			(at 0 0 90)
			(layer "F.Fab")
			(effects
				(font
					(size 1.27 1.27)
				)
			)
		)
		(duplicate_pad_numbers_are_jumpers no)
		(fp_line
			(start 0.7874 -0.4064)
			(end 0.7874 0.4064)
			(stroke
				(width 0.1524)
				(type default)
			)
			(layer "F.SilkS")
		)
		(fp_line
			(start -0.7874 -0.4064)
			(end 0.7874 -0.4064)
			(stroke
				(width 0.1524)
				(type default)
			)
			(layer "F.SilkS")
		)
		(fp_line
			(start 0.7874 0.4064)
			(end -0.7874 0.4064)
			(stroke
				(width 0.1524)
				(type default)
			)
			(layer "F.SilkS")
		)
		(fp_line
			(start -0.7874 0.4064)
			(end -0.7874 -0.4064)
			(stroke
				(width 0.1524)
				(type default)
			)
			(layer "F.SilkS")
		)
		(fp_line
			(start -0.12065 -0.305054)
			(end -0.12065 -0.2794)
			(stroke
				(width 0.1)
				(type default)
			)
			(layer "F.Fab")
		)
		(fp_line
			(start -0.67945 -0.305054)
			(end -0.12065 -0.305054)
			(stroke
				(width 0.1)
				(type default)
			)
			(layer "F.Fab")
		)
		(fp_line
			(start 0.67945 -0.3048)
			(end 0.67945 0.3048)
			(stroke
				(width 0.1)
				(type default)
			)
			(layer "F.Fab")
		)
		(fp_line
			(start 0.12065 -0.3048)
			(end 0.67945 -0.3048)
			(stroke
				(width 0.1)
				(type default)
			)
			(layer "F.Fab")
		)
		(fp_line
			(start 0.12065 -0.2794)
			(end 0.12065 -0.3048)
			(stroke
				(width 0.1)
				(type default)
			)
			(layer "F.Fab")
		)
		(fp_line
			(start -0.12065 -0.2794)
			(end 0.12065 -0.2794)
			(stroke
				(width 0.1)
				(type default)
			)
			(layer "F.Fab")
		)
		(fp_line
			(start 0.120396 0.2794)
			(end -0.12065 0.2794)
			(stroke
				(width 0.1)
				(type default)
			)
			(layer "F.Fab")
		)
		(fp_line
			(start -0.12065 0.2794)
			(end -0.12065 0.3048)
			(stroke
				(width 0.1)
				(type default)
			)
			(layer "F.Fab")
		)
		(fp_line
			(start 0.67945 0.3048)
			(end 0.120396 0.3048)
			(stroke
				(width 0.1)
				(type default)
			)
			(layer "F.Fab")
		)
		(fp_line
			(start 0.120396 0.3048)
			(end 0.120396 0.2794)
			(stroke
				(width 0.1)
				(type default)
			)
			(layer "F.Fab")
		)
		(fp_line
			(start -0.12065 0.3048)
			(end -0.67945 0.3048)
			(stroke
				(width 0.1)
				(type default)
			)
			(layer "F.Fab")
		)
		(fp_line
			(start -0.67945 0.3048)
			(end -0.67945 -0.305054)
			(stroke
				(width 0.1)
				(type default)
			)
			(layer "F.Fab")
		)
		(pad "1" smd circle
			(at -0.40005 0 90)
			(size 0 0)
			(layers "F.Cu" "F.Mask" "F.Paste")
			(net "SMB_VR_3V3AUX_SDA_R")
		)
		(pad "2" smd circle
			(at 0.40005 0 90)
			(size 0 0)
			(layers "F.Cu" "F.Mask" "F.Paste")
			(net "SMB_DIO_PVCCINFAON_CPU1")
		)
	)
)
